(kicad_pcb
	(version 20260206)
	(generator "pcbnew")
	(generator_version "10.0")
	(general
		(thickness 1.6)
		(legacy_teardrops no)
	)
	(paper "A4")
	(title_block
		(title "Bryce Canyon_F.DPB_16315-1-OCP.brd")
		(comment 1 "Bryce Canyon / footprints 498-504 of 2223")
	)
	(layers
		(0 "F.Cu" signal "TOP")
		(4 "In1.Cu" signal "L2GND")
		(6 "In2.Cu" signal "L3")
		(8 "In3.Cu" signal "L4GND")
		(10 "In4.Cu" signal "L5")
		(12 "In5.Cu" signal "L6VCC")
		(14 "In6.Cu" signal "L7VCC")
		(16 "In7.Cu" signal "L8")
		(18 "In8.Cu" signal "L9GND")
		(20 "In9.Cu" signal "L10")
		(22 "In10.Cu" signal "L11GND")
		(2 "B.Cu" signal "BOTTOM")
		(9 "F.Adhes" user "F.Adhesive")
		(11 "B.Adhes" user "B.Adhesive")
		(13 "F.Paste" user "Package Geometry/Pastemask Top")
		(15 "B.Paste" user "Package Geometry/Pastemask Bottom")
		(5 "F.SilkS" user "Ref Des/Silkscreen Top")
		(7 "B.SilkS" user "Ref Des/Silkscreen Bottom")
		(1 "F.Mask" user "Board Geometry/Soldermask Top")
		(3 "B.Mask" user "Board Geometry/Soldermask Bottom")
		(17 "Dwgs.User" user "User.Drawings")
		(19 "Cmts.User" user "User.Comments")
		(21 "Eco1.User" user "User.Eco1")
		(23 "Eco2.User" user "User.Eco2")
		(25 "Edge.Cuts" user "Board Geometry/Outline")
		(27 "Margin" user)
		(31 "F.CrtYd" user "Package Geometry/Place Bound Top")
		(29 "B.CrtYd" user "Package Geometry/Place Bound Bottom")
		(35 "F.Fab" user "Ref Des/Assembly Top")
		(33 "B.Fab" user "Ref Des/Assembly Bottom")
	)
	(footprint ""
		(layer "F.Cu")
		(at 441.349892 -209.399886)
		(property "Reference" "FLED11"
			(at 0 0 0)
			(layer "F.SilkS")
			(hide yes)
			(effects
				(font
					(size 1.27 1.27)
				)
			)
		)
		(property "Value" "LED-BY-19-GP"
			(at -2.132076 1.414018 0)
			(unlocked yes)
			(layer "F.Fab")
			(hide yes)
			(effects
				(font
					(size 1.016 1.016)
					(thickness 0.1524)
				)
			)
		)
		(property "Device Type" "LED-1615-4PH26"
			(at -2.132076 -0.109982 0)
			(unlocked yes)
			(layer "F.Fab")
			(hide yes)
			(effects
				(font
					(size 1.016 1.016)
					(thickness 0.1524)
				)
			)
		)
		(duplicate_pad_numbers_are_jumpers no)
		(fp_line
			(start -1.2954 0.254)
			(end -1.2954 1.6002)
			(stroke
				(width 0.508)
				(type default)
			)
			(layer "F.SilkS")
		)
		(fp_line
			(start -1.2954 1.6002)
			(end 1.2954 1.6002)
			(stroke
				(width 0.508)
				(type default)
			)
			(layer "F.SilkS")
		)
		(fp_line
			(start -1.1176 -1.4224)
			(end 1.1176 -1.4224)
			(stroke
				(width 0.1524)
				(type default)
			)
			(layer "F.SilkS")
		)
		(fp_line
			(start -1.1176 1.4224)
			(end -1.1176 -1.4224)
			(stroke
				(width 0.1524)
				(type default)
			)
			(layer "F.SilkS")
		)
		(fp_line
			(start 1.1176 -1.4224)
			(end 1.1176 1.4224)
			(stroke
				(width 0.1524)
				(type default)
			)
			(layer "F.SilkS")
		)
		(fp_line
			(start 1.1176 1.4224)
			(end -1.1176 1.4224)
			(stroke
				(width 0.1524)
				(type default)
			)
			(layer "F.SilkS")
		)
		(fp_line
			(start 1.2954 1.6002)
			(end 1.2954 0.254)
			(stroke
				(width 0.508)
				(type default)
			)
			(layer "F.SilkS")
		)
		(fp_rect
			(start -0.7493 0.8001)
			(end 0.7493 -0.8001)
			(stroke
				(width 0)
				(type default)
			)
			(fill no)
			(layer "F.CrtYd")
		)
		(fp_poly
			(pts
				(xy -1.3716 1.6764) (xy -1.3716 -1.6764) (xy 1.3716 -1.6764) (xy 1.3716 0.0635) (xy 0.7493 0.0635)
				(xy 0.7493 -0.8001) (xy -0.7493 -0.8001) (xy -0.7493 0.8001) (xy 0.7493 0.8001) (xy 0.7493 0.0762)
				(xy 1.3716 0.0762) (xy 1.3716 1.6764)
			)
			(stroke
				(width 0)
				(type default)
			)
			(fill no)
			(layer "F.CrtYd")
		)
		(fp_rect
			(start -1.3716 1.6764)
			(end 1.3716 -1.6764)
			(stroke
				(width 0)
				(type default)
			)
			(fill no)
			(layer "F.Fab")
		)
		(pad "1" smd rect
			(at 0.50038 -0.73025)
			(size 0.7112 0.8636)
			(layers "F.Cu" "F.Mask" "F.Paste")
			(net "DRV_ACT_10")
		)
		(pad "2" smd rect
			(at -0.50038 -0.73025)
			(size 0.7112 0.8636)
			(layers "F.Cu" "F.Mask" "F.Paste")
			(net "FLT_HDD10")
		)
		(pad "3" smd rect
			(at 0.50038 0.73025)
			(size 0.7112 0.8636)
			(layers "F.Cu" "F.Mask" "F.Paste")
			(net "DRV_ACT_10_N")
		)
		(pad "4" smd rect
			(at -0.50038 0.73025)
			(size 0.7112 0.8636)
			(layers "F.Cu" "F.Mask" "F.Paste")
			(net "FLT_HDD10_N")
		)
	)
	(footprint ""
		(layer "F.Cu")
		(at 392.91895 -189.335918 180)
		(property "Reference" "C307"
			(at 0 0 180)
			(layer "F.SilkS")
			(hide yes)
			(effects
				(font
					(size 1.27 1.27)
				)
			)
		)
		(property "Value" "SC1U25V3KX-GP"
			(at 0 -2.8194 180)
			(unlocked yes)
			(layer "F.Fab")
			(hide yes)
			(effects
				(font
					(size 1.016 1.016)
					(thickness 0.1524)
				)
			)
		)
		(property "Device Type" "C603H36"
			(at 0 -4.3434 180)
			(unlocked yes)
			(layer "F.Fab")
			(hide yes)
			(effects
				(font
					(size 1.016 1.016)
					(thickness 0.1524)
				)
			)
		)
		(duplicate_pad_numbers_are_jumpers no)
		(fp_line
			(start 0.508 0)
			(end -0.508 0)
			(stroke
				(width 0.2032)
				(type default)
			)
			(layer "F.SilkS")
		)
		(fp_rect
			(start -0.5842 1.3335)
			(end 0.5842 -1.3335)
			(stroke
				(width 0)
				(type default)
			)
			(fill no)
			(layer "F.CrtYd")
		)
		(fp_rect
			(start -0.5842 1.3335)
			(end 0.5842 -1.3335)
			(stroke
				(width 0)
				(type default)
			)
			(fill no)
			(layer "F.Fab")
		)
		(pad "1" smd custom
			(at 0 -0.762 180)
			(size 0.2159 0.2159)
			(layers "F.Cu" "F.Mask" "F.Paste")
			(net "P12V_HDD20")
			(options
				(clearance outline)
				(anchor circle)
			)
			(primitives
				(gr_poly
					(pts
						(arc
							(start -0.3302 -0.4318)
							(mid -0.402042 -0.402042)
							(end -0.4318 -0.3302)
						)
						(arc
							(start -0.4318 0.3302)
							(mid -0.402042 0.402042)
							(end -0.3302 0.4318)
						)
						(arc
							(start 0.3302 0.4318)
							(mid 0.402042 0.402042)
							(end 0.4318 0.3302)
						)
						(arc
							(start 0.4318 -0.3302)
							(mid 0.402042 -0.402042)
							(end 0.3302 -0.4318)
						)
					)
					(width 0)
					(fill yes)
				)
			)
		)
		(pad "2" smd custom
			(at 0 0.762 180)
			(size 0.2159 0.2159)
			(layers "F.Cu" "F.Mask" "F.Paste")
			(net "GND")
			(options
				(clearance outline)
				(anchor circle)
			)
			(primitives
				(gr_poly
					(pts
						(arc
							(start -0.3302 -0.4318)
							(mid -0.402042 -0.402042)
							(end -0.4318 -0.3302)
						)
						(arc
							(start -0.4318 0.3302)
							(mid -0.402042 0.402042)
							(end -0.3302 0.4318)
						)
						(arc
							(start 0.3302 0.4318)
							(mid 0.402042 0.402042)
							(end 0.4318 0.3302)
						)
						(arc
							(start 0.4318 -0.3302)
							(mid 0.402042 -0.402042)
							(end 0.3302 -0.4318)
						)
					)
					(width 0)
					(fill yes)
				)
			)
		)
	)
	(footprint ""
		(layer "F.Cu")
		(at 244.725952 -385.759706)
		(property "Reference" "R1139"
			(at 0 0 0)
			(layer "F.SilkS")
			(hide yes)
			(effects
				(font
					(size 1.27 1.27)
				)
			)
		)
		(property "Value" "100R2D-GP"
			(at 0.064008 -3.993896 0)
			(unlocked yes)
			(layer "F.Fab")
			(hide yes)
			(effects
				(font
					(size 1.016 1.016)
					(thickness 0.1524)
				)
			)
		)
		(property "Device Type" "R402H14"
			(at 0.064008 -5.517896 0)
			(unlocked yes)
			(layer "F.Fab")
			(hide yes)
			(effects
				(font
					(size 1.016 1.016)
					(thickness 0.1524)
				)
			)
		)
		(duplicate_pad_numbers_are_jumpers no)
		(fp_line
			(start -0.508 -0.9398)
			(end -0.508 0.9398)
			(stroke
				(width 0.1524)
				(type default)
			)
			(layer "F.SilkS")
		)
		(fp_line
			(start 0.508 -0.9398)
			(end -0.508 -0.9398)
			(stroke
				(width 0.1524)
				(type default)
			)
			(layer "F.SilkS")
		)
		(fp_rect
			(start -0.508 0.9398)
			(end 0.508 -0.9398)
			(stroke
				(width 0)
				(type default)
			)
			(fill no)
			(layer "F.CrtYd")
		)
		(fp_rect
			(start -0.508 0.9398)
			(end 0.508 -0.9398)
			(stroke
				(width 0)
				(type default)
			)
			(fill no)
			(layer "F.Fab")
		)
		(pad "1" smd custom
			(at 0 -0.4445)
			(size 0.1397 0.1397)
			(layers "F.Cu" "F.Mask" "F.Paste")
			(net "MB3_TEMP")
			(options
				(clearance outline)
				(anchor circle)
			)
			(primitives
				(gr_poly
					(pts
						(arc
							(start -0.1778 -0.2794)
							(mid -0.249642 -0.249642)
							(end -0.2794 -0.1778)
						)
						(arc
							(start -0.2794 0.1778)
							(mid -0.249642 0.249642)
							(end -0.1778 0.2794)
						)
						(arc
							(start 0.1778 0.2794)
							(mid 0.249642 0.249642)
							(end 0.2794 0.1778)
						)
						(arc
							(start 0.2794 -0.1778)
							(mid 0.249642 -0.249642)
							(end 0.1778 -0.2794)
						)
					)
					(width 0)
					(fill yes)
				)
			)
		)
		(pad "2" smd custom
			(at 0 0.4445)
			(size 0.1397 0.1397)
			(layers "F.Cu" "F.Mask" "F.Paste")
			(net "MB3_TEMP_B")
			(options
				(clearance outline)
				(anchor circle)
			)
			(primitives
				(gr_poly
					(pts
						(arc
							(start -0.1778 -0.2794)
							(mid -0.249642 -0.249642)
							(end -0.2794 -0.1778)
						)
						(arc
							(start -0.2794 0.1778)
							(mid -0.249642 0.249642)
							(end -0.1778 0.2794)
						)
						(arc
							(start 0.1778 0.2794)
							(mid 0.249642 0.249642)
							(end 0.2794 0.1778)
						)
						(arc
							(start 0.2794 -0.1778)
							(mid 0.249642 -0.249642)
							(end 0.1778 -0.2794)
						)
					)
					(width 0)
					(fill yes)
				)
			)
		)
	)
	(footprint ""
		(layer "F.Cu")
		(at 146.630898 -163.554918 180)
		(property "Reference" "Q97"
			(at 0 0 180)
			(layer "F.SilkS")
			(hide yes)
			(effects
				(font
					(size 1.27 1.27)
				)
			)
		)
		(property "Value" "2N7002KDW-GP"
			(at -2.3622 -8.2042 180)
			(unlocked yes)
			(layer "F.Fab")
			(hide yes)
			(effects
				(font
					(size 1.016 1.016)
					(thickness 0.1524)
				)
			)
		)
		(property "Device Type" "SOT-363H44"
			(at -2.3622 -10.1092 180)
			(unlocked yes)
			(layer "F.Fab")
			(hide yes)
			(effects
				(font
					(size 1.016 1.016)
					(thickness 0.1524)
				)
			)
		)
		(duplicate_pad_numbers_are_jumpers no)
		(fp_line
			(start 1.4478 1.7018)
			(end 1.4478 -1.7018)
			(stroke
				(width 0.1524)
				(type default)
			)
			(layer "F.SilkS")
		)
		(fp_line
			(start 1.4478 -1.7018)
			(end -1.4478 -1.7018)
			(stroke
				(width 0.1524)
				(type default)
			)
			(layer "F.SilkS")
		)
		(fp_line
			(start -1.27 1.524)
			(end -1.27 0.6604)
			(stroke
				(width 0.4826)
				(type default)
			)
			(layer "F.SilkS")
		)
		(fp_line
			(start -1.4478 1.7018)
			(end 1.4478 1.7018)
			(stroke
				(width 0.1524)
				(type default)
			)
			(layer "F.SilkS")
		)
		(fp_line
			(start -1.4478 -1.7018)
			(end -1.4478 1.7018)
			(stroke
				(width 0.1524)
				(type default)
			)
			(layer "F.SilkS")
		)
		(fp_poly
			(pts
				(xy -1.524 -1.778) (xy 1.524 -1.778) (xy 1.524 1.778) (xy -1.524 1.778)
			)
			(stroke
				(width 0)
				(type default)
			)
			(fill no)
			(layer "F.CrtYd")
		)
		(fp_poly
			(pts
				(xy -1.524 -1.778) (xy 1.524 -1.778) (xy 1.524 1.778) (xy -1.524 1.778)
			)
			(stroke
				(width 0)
				(type default)
			)
			(fill no)
			(layer "F.Fab")
		)
		(pad "1" smd rect
			(at -0.65024 0.9398 180)
			(size 0.4064 1.016)
			(layers "F.Cu" "F.Mask" "F.Paste")
			(net "GND")
		)
		(pad "2" smd rect
			(at 0 0.9398 180)
			(size 0.4064 1.016)
			(layers "F.Cu" "F.Mask" "F.Paste")
			(net "SW_PWR_R_HDD16")
		)
		(pad "3" smd rect
			(at 0.65024 0.9398 180)
			(size 0.4064 1.016)
			(layers "F.Cu" "F.Mask" "F.Paste")
			(net "SW_HDD_P16")
		)
		(pad "4" smd rect
			(at 0.65024 -0.9398 180)
			(size 0.4064 1.016)
			(layers "F.Cu" "F.Mask" "F.Paste")
			(net "GND")
		)
		(pad "5" smd rect
			(at 0 -0.9398 180)
			(size 0.4064 1.016)
			(layers "F.Cu" "F.Mask" "F.Paste")
			(net "SW_HDD_G16")
		)
		(pad "6" smd rect
			(at -0.65024 -0.9398 180)
			(size 0.4064 1.016)
			(layers "F.Cu" "F.Mask" "F.Paste")
			(net "SW_HDD_R16")
		)
	)
	(footprint ""
		(layer "F.Cu")
		(at 314.2361 -59.2582 -90)
		(property "Reference" "U42"
			(at 0 0 270)
			(layer "F.SilkS")
			(hide yes)
			(effects
				(font
					(size 1.27 1.27)
				)
			)
		)
		(property "Value" "SNLVC1G126DCKR-GP"
			(at -2.3368 -8.6868 270)
			(unlocked yes)
			(layer "F.Fab")
			(hide yes)
			(effects
				(font
					(size 1.016 1.016)
					(thickness 0.1524)
				)
			)
		)
		(property "Device Type" "SC70-5H44"
			(at -2.3114 -10.414 270)
			(unlocked yes)
			(layer "F.Fab")
			(hide yes)
			(effects
				(font
					(size 1.016 1.016)
					(thickness 0.1524)
				)
			)
		)
		(duplicate_pad_numbers_are_jumpers no)
		(fp_line
			(start -1.27 1.7018)
			(end -1.27 -1.7018)
			(stroke
				(width 0.1524)
				(type default)
			)
			(layer "F.SilkS")
		)
		(fp_line
			(start 1.27 1.7018)
			(end -1.27 1.7018)
			(stroke
				(width 0.1524)
				(type default)
			)
			(layer "F.SilkS")
		)
		(fp_line
			(start -1.27 -1.7018)
			(end 1.27 -1.7018)
			(stroke
				(width 0.1524)
				(type default)
			)
			(layer "F.SilkS")
		)
		(fp_line
			(start 1.27 -1.7018)
			(end 1.27 1.7018)
			(stroke
				(width 0.1524)
				(type default)
			)
			(layer "F.SilkS")
		)
		(fp_line
			(start 0.6604 -1.8034)
			(end 1.3843 -1.8034)
			(stroke
				(width 0.3302)
				(type default)
			)
			(layer "F.SilkS")
		)
		(fp_line
			(start 1.3843 -1.8034)
			(end 1.3843 -1.1176)
			(stroke
				(width 0.3302)
				(type default)
			)
			(layer "F.SilkS")
		)
		(fp_rect
			(start -1.524 1.9558)
			(end 1.524 -1.9558)
			(stroke
				(width 0)
				(type default)
			)
			(fill no)
			(layer "F.CrtYd")
		)
		(fp_poly
			(pts
				(xy -1.524 -1.9558) (xy 1.524 -1.9558) (xy 1.524 1.9558) (xy -1.524 1.9558)
			)
			(stroke
				(width 0)
				(type default)
			)
			(fill no)
			(layer "F.Fab")
		)
		(pad "1" smd rect
			(at 0.65024 -0.8255 270)
			(size 0.4064 1.2192)
			(layers "F.Cu" "F.Mask" "F.Paste")
			(net "P3V3_STBY_B")
		)
		(pad "2" smd rect
			(at 0 -0.8255 270)
			(size 0.4064 1.2192)
			(layers "F.Cu" "F.Mask" "F.Paste")
			(net "SYS_B_RESET_N")
		)
		(pad "3" smd rect
			(at -0.65024 -0.8255 270)
			(size 0.4064 1.2192)
			(layers "F.Cu" "F.Mask" "F.Paste")
			(net "GND")
		)
		(pad "4" smd rect
			(at -0.65024 0.8255 270)
			(size 0.4064 1.2192)
			(layers "F.Cu" "F.Mask" "F.Paste")
			(net "SYS_B_RESET_BUFFER_N")
		)
		(pad "5" smd rect
			(at 0.65024 0.8255 270)
			(size 0.4064 1.2192)
			(layers "F.Cu" "F.Mask" "F.Paste")
			(net "P3V3_STBY_B")
		)
	)
	(footprint ""
		(layer "F.Cu")
		(at 318.77 -62.194694 90)
		(property "Reference" "R820"
			(at 0 0 90)
			(layer "F.SilkS")
			(hide yes)
			(effects
				(font
					(size 1.27 1.27)
				)
			)
		)
		(property "Value" "10KR2F-2-GP"
			(at 0.064008 -3.993896 90)
			(unlocked yes)
			(layer "F.Fab")
			(hide yes)
			(effects
				(font
					(size 1.016 1.016)
					(thickness 0.1524)
				)
			)
		)
		(property "Device Type" "R402H16"
			(at 0.064008 -5.517896 90)
			(unlocked yes)
			(layer "F.Fab")
			(hide yes)
			(effects
				(font
					(size 1.016 1.016)
					(thickness 0.1524)
				)
			)
		)
		(duplicate_pad_numbers_are_jumpers no)
		(fp_line
			(start 0.508 -0.9398)
			(end -0.508 -0.9398)
			(stroke
				(width 0.1524)
				(type default)
			)
			(layer "F.SilkS")
		)
		(fp_line
			(start -0.508 -0.9398)
			(end -0.508 0.9398)
			(stroke
				(width 0.1524)
				(type default)
			)
			(layer "F.SilkS")
		)
		(fp_rect
			(start -0.508 0.9398)
			(end 0.508 -0.9398)
			(stroke
				(width 0)
				(type default)
			)
			(fill no)
			(layer "F.CrtYd")
		)
		(fp_rect
			(start -0.508 0.9398)
			(end 0.508 -0.9398)
			(stroke
				(width 0)
				(type default)
			)
			(fill no)
			(layer "F.Fab")
		)
		(pad "1" smd custom
			(at 0 -0.4445 90)
			(size 0.1397 0.1397)
			(layers "F.Cu" "F.Mask" "F.Paste")
			(net "P3V3_STBY_A")
			(options
				(clearance outline)
				(anchor circle)
			)
			(primitives
				(gr_poly
					(pts
						(arc
							(start -0.1778 -0.2794)
							(mid -0.249642 -0.249642)
							(end -0.2794 -0.1778)
						)
						(arc
							(start -0.2794 0.1778)
							(mid -0.249642 0.249642)
							(end -0.1778 0.2794)
						)
						(arc
							(start 0.1778 0.2794)
							(mid 0.249642 0.249642)
							(end 0.2794 0.1778)
						)
						(arc
							(start 0.2794 -0.1778)
							(mid 0.249642 -0.249642)
							(end 0.1778 -0.2794)
						)
					)
					(width 0)
					(fill yes)
				)
			)
		)
		(pad "2" smd custom
			(at 0 0.4445 90)
			(size 0.1397 0.1397)
			(layers "F.Cu" "F.Mask" "F.Paste")
			(net "HDD_PRSNT_30")
			(options
				(clearance outline)
				(anchor circle)
			)
			(primitives
				(gr_poly
					(pts
						(arc
							(start -0.1778 -0.2794)
							(mid -0.249642 -0.249642)
							(end -0.2794 -0.1778)
						)
						(arc
							(start -0.2794 0.1778)
							(mid -0.249642 0.249642)
							(end -0.1778 0.2794)
						)
						(arc
							(start 0.1778 0.2794)
							(mid 0.249642 0.249642)
							(end 0.2794 0.1778)
						)
						(arc
							(start 0.2794 -0.1778)
							(mid 0.249642 -0.249642)
							(end 0.1778 -0.2794)
						)
					)
					(width 0)
					(fill yes)
				)
			)
		)
	)
	(footprint ""
		(layer "F.Cu")
		(at 98.897948 -62.169294 -90)
		(property "Reference" "R728"
			(at 0 0 270)
			(layer "F.SilkS")
			(hide yes)
			(effects
				(font
					(size 1.27 1.27)
				)
			)
		)
		(property "Value" "10KR2F-2-GP"
			(at 0.064008 -3.993896 270)
			(unlocked yes)
			(layer "F.Fab")
			(hide yes)
			(effects
				(font
					(size 1.016 1.016)
					(thickness 0.1524)
				)
			)
		)
		(property "Device Type" "R402H16"
			(at 0.064008 -5.517896 270)
			(unlocked yes)
			(layer "F.Fab")
			(hide yes)
			(effects
				(font
					(size 1.016 1.016)
					(thickness 0.1524)
				)
			)
		)
		(duplicate_pad_numbers_are_jumpers no)
		(fp_line
			(start -0.508 -0.9398)
			(end -0.508 0.9398)
			(stroke
				(width 0.1524)
				(type default)
			)
			(layer "F.SilkS")
		)
		(fp_line
			(start 0.508 -0.9398)
			(end -0.508 -0.9398)
			(stroke
				(width 0.1524)
				(type default)
			)
			(layer "F.SilkS")
		)
		(fp_rect
			(start -0.508 0.9398)
			(end 0.508 -0.9398)
			(stroke
				(width 0)
				(type default)
			)
			(fill no)
			(layer "F.CrtYd")
		)
		(fp_rect
			(start -0.508 0.9398)
			(end 0.508 -0.9398)
			(stroke
				(width 0)
				(type default)
			)
			(fill no)
			(layer "F.Fab")
		)
		(pad "1" smd custom
			(at 0 -0.4445 270)
			(size 0.1397 0.1397)
			(layers "F.Cu" "F.Mask" "F.Paste")
			(net "P3V3_STBY_A")
			(options
				(clearance outline)
				(anchor circle)
			)
			(primitives
				(gr_poly
					(pts
						(arc
							(start -0.1778 -0.2794)
							(mid -0.249642 -0.249642)
							(end -0.2794 -0.1778)
						)
						(arc
							(start -0.2794 0.1778)
							(mid -0.249642 0.249642)
							(end -0.1778 0.2794)
						)
						(arc
							(start 0.1778 0.2794)
							(mid 0.249642 0.249642)
							(end 0.2794 0.1778)
						)
						(arc
							(start 0.2794 -0.1778)
							(mid 0.249642 -0.249642)
							(end 0.1778 -0.2794)
						)
					)
					(width 0)
					(fill yes)
				)
			)
		)
		(pad "2" smd custom
			(at 0 0.4445 270)
			(size 0.1397 0.1397)
			(layers "F.Cu" "F.Mask" "F.Paste")
			(net "HDD_PRSNT_26")
			(options
				(clearance outline)
				(anchor circle)
			)
			(primitives
				(gr_poly
					(pts
						(arc
							(start -0.1778 -0.2794)
							(mid -0.249642 -0.249642)
							(end -0.2794 -0.1778)
						)
						(arc
							(start -0.2794 0.1778)
							(mid -0.249642 0.249642)
							(end -0.1778 0.2794)
						)
						(arc
							(start 0.1778 0.2794)
							(mid 0.249642 0.249642)
							(end 0.2794 0.1778)
						)
						(arc
							(start 0.2794 -0.1778)
							(mid 0.249642 -0.249642)
							(end 0.1778 -0.2794)
						)
					)
					(width 0)
					(fill yes)
				)
			)
		)
	)
)
